(kicad_pcb
	(version 20260206)
	(generator "pcbnew")
	(generator_version "10.0")
	(general
		(thickness 1.6)
		(legacy_teardrops no)
	)
	(paper "A4")
	(title_block
		(title "Bryce Canyon_SCC_16316-1_OCP.brd")
		(comment 1 "Bryce Canyon / footprints 1513-1519 of 1561")
	)
	(layers
		(0 "F.Cu" signal "TOP")
		(4 "In1.Cu" signal "L2GND")
		(6 "In2.Cu" signal "L3")
		(8 "In3.Cu" signal "L4VCC")
		(10 "In4.Cu" signal "L5VCC")
		(12 "In5.Cu" signal "L6")
		(14 "In6.Cu" signal "L7GND")
		(2 "B.Cu" signal "BOTTOM")
		(9 "F.Adhes" user "F.Adhesive")
		(11 "B.Adhes" user "B.Adhesive")
		(13 "F.Paste" user "Package Geometry/Pastemask Top")
		(15 "B.Paste" user "Package Geometry/Pastemask Bottom")
		(5 "F.SilkS" user "Ref Des/Silkscreen Top")
		(7 "B.SilkS" user "Ref Des/Silkscreen Bottom")
		(1 "F.Mask" user "Board Geometry/Soldermask Top")
		(3 "B.Mask" user "Board Geometry/Soldermask Bottom")
		(17 "Dwgs.User" user "User.Drawings")
		(19 "Cmts.User" user "User.Comments")
		(21 "Eco1.User" user "User.Eco1")
		(23 "Eco2.User" user "User.Eco2")
		(25 "Edge.Cuts" user "Board Geometry/Outline")
		(27 "Margin" user)
		(31 "F.CrtYd" user "Package Geometry/Place Bound Top")
		(29 "B.CrtYd" user "Package Geometry/Place Bound Bottom")
		(35 "F.Fab" user "Ref Des/Assembly Top")
		(33 "B.Fab" user "Ref Des/Assembly Bottom")
	)
	(footprint ""
		(layer "B.Cu")
		(at 202.311 -58.674)
		(property "Reference" "R304"
			(at 0 0 0)
			(layer "B.SilkS")
			(hide yes)
			(effects
				(font
					(size 1.27 1.27)
				)
				(justify mirror)
			)
		)
		(property "Value" "10KR2F-2-GP"
			(at -0.064008 -3.993896 0)
			(unlocked yes)
			(layer "B.Fab")
			(hide yes)
			(effects
				(font
					(size 1.016 1.016)
					(thickness 0.1524)
				)
				(justify mirror)
			)
		)
		(property "Device Type" "R402H16"
			(at -0.064008 -5.517896 0)
			(unlocked yes)
			(layer "B.Fab")
			(hide yes)
			(effects
				(font
					(size 1.016 1.016)
					(thickness 0.1524)
				)
				(justify mirror)
			)
		)
		(duplicate_pad_numbers_are_jumpers no)
		(fp_line
			(start -0.508 -0.9398)
			(end 0.508 -0.9398)
			(stroke
				(width 0.1524)
				(type default)
			)
			(layer "B.SilkS")
		)
		(fp_line
			(start 0.508 -0.9398)
			(end 0.508 0.9398)
			(stroke
				(width 0.1524)
				(type default)
			)
			(layer "B.SilkS")
		)
		(fp_rect
			(start 0.508 0.9398)
			(end -0.508 -0.9398)
			(stroke
				(width 0)
				(type default)
			)
			(fill no)
			(layer "B.CrtYd")
		)
		(fp_rect
			(start 0.508 0.9398)
			(end -0.508 -0.9398)
			(stroke
				(width 0)
				(type default)
			)
			(fill no)
			(layer "B.Fab")
		)
		(pad "1" smd custom
			(at 0 -0.4445 180)
			(size 0.1397 0.1397)
			(layers "B.Cu" "B.Mask" "B.Paste")
			(net "IOC_BYTE_N")
			(options
				(clearance outline)
				(anchor circle)
			)
			(primitives
				(gr_poly
					(pts
						(arc
							(start -0.1778 0.2794)
							(mid -0.249642 0.249642)
							(end -0.2794 0.1778)
						)
						(arc
							(start -0.2794 -0.1778)
							(mid -0.249642 -0.249642)
							(end -0.1778 -0.2794)
						)
						(arc
							(start 0.1778 -0.2794)
							(mid 0.249642 -0.249642)
							(end 0.2794 -0.1778)
						)
						(arc
							(start 0.2794 0.1778)
							(mid 0.249642 0.249642)
							(end 0.1778 0.2794)
						)
					)
					(width 0)
					(fill yes)
				)
			)
		)
		(pad "2" smd custom
			(at 0 0.4445 180)
			(size 0.1397 0.1397)
			(layers "B.Cu" "B.Mask" "B.Paste")
			(net "GND")
			(options
				(clearance outline)
				(anchor circle)
			)
			(primitives
				(gr_poly
					(pts
						(arc
							(start -0.1778 0.2794)
							(mid -0.249642 0.249642)
							(end -0.2794 0.1778)
						)
						(arc
							(start -0.2794 -0.1778)
							(mid -0.249642 -0.249642)
							(end -0.1778 -0.2794)
						)
						(arc
							(start 0.1778 -0.2794)
							(mid 0.249642 -0.249642)
							(end 0.2794 -0.1778)
						)
						(arc
							(start 0.2794 0.1778)
							(mid 0.249642 0.249642)
							(end 0.1778 0.2794)
						)
					)
					(width 0)
					(fill yes)
				)
			)
		)
	)
	(footprint ""
		(layer "B.Cu")
		(at 202.057 -19.939 90)
		(property "Reference" "Q6"
			(at 0 0 90)
			(layer "B.SilkS")
			(hide yes)
			(effects
				(font
					(size 1.27 1.27)
				)
				(justify mirror)
			)
		)
		(property "Value" "2N7002K-1-GP"
			(at -0.127 -8.9662 90)
			(unlocked yes)
			(layer "B.Fab")
			(hide yes)
			(effects
				(font
					(size 1.016 1.016)
					(thickness 0.1524)
				)
				(justify mirror)
			)
		)
		(property "Device Type" "SOT23DGS2D4H44"
			(at -0.127 -10.4902 90)
			(unlocked yes)
			(layer "B.Fab")
			(hide yes)
			(effects
				(font
					(size 1.016 1.016)
					(thickness 0.1524)
				)
				(justify mirror)
			)
		)
		(duplicate_pad_numbers_are_jumpers no)
		(fp_line
			(start 1.651 -1.778)
			(end 1.651 1.778)
			(stroke
				(width 0.1524)
				(type default)
			)
			(layer "B.SilkS")
		)
		(fp_line
			(start -1.651 -1.778)
			(end 1.651 -1.778)
			(stroke
				(width 0.1524)
				(type default)
			)
			(layer "B.SilkS")
		)
		(fp_line
			(start 1.651 1.778)
			(end -1.651 1.778)
			(stroke
				(width 0.1524)
				(type default)
			)
			(layer "B.SilkS")
		)
		(fp_line
			(start -1.651 1.778)
			(end -1.651 -1.778)
			(stroke
				(width 0.1524)
				(type default)
			)
			(layer "B.SilkS")
		)
		(fp_poly
			(pts
				(xy 1.778 1.8796) (xy 1.778 -1.8796) (xy -1.778 -1.8796) (xy -1.778 1.8796)
			)
			(stroke
				(width 0)
				(type default)
			)
			(fill no)
			(layer "B.CrtYd")
		)
		(fp_poly
			(pts
				(xy 1.778 1.8796) (xy 1.778 -1.8796) (xy -1.778 -1.8796) (xy -1.778 1.8796)
			)
			(stroke
				(width 0)
				(type default)
			)
			(fill no)
			(layer "B.Fab")
		)
		(pad "D" smd custom
			(at 0 -0.9525 270)
			(size 0.1905 0.1905)
			(layers "B.Cu" "B.Mask" "B.Paste")
			(net "P3V3_STBY_R")
			(options
				(clearance outline)
				(anchor circle)
			)
			(primitives
				(gr_poly
					(pts
						(arc
							(start -0.1778 -0.5715)
							(mid -0.321484 -0.511984)
							(end -0.381 -0.3683)
						)
						(arc
							(start -0.381 0.3683)
							(mid -0.321484 0.511984)
							(end -0.1778 0.5715)
						)
						(arc
							(start 0.1778 0.5715)
							(mid 0.321484 0.511984)
							(end 0.381 0.3683)
						)
						(arc
							(start 0.381 -0.3683)
							(mid 0.321484 -0.511984)
							(end 0.1778 -0.5715)
						)
					)
					(width 0)
					(fill yes)
				)
			)
		)
		(pad "G" smd custom
			(at 0.98425 0.9525 270)
			(size 0.1905 0.1905)
			(layers "B.Cu" "B.Mask" "B.Paste")
			(net "PCIE_COMP_TO_SCC_RST_0")
			(options
				(clearance outline)
				(anchor circle)
			)
			(primitives
				(gr_poly
					(pts
						(arc
							(start -0.1778 -0.5715)
							(mid -0.321484 -0.511984)
							(end -0.381 -0.3683)
						)
						(arc
							(start -0.381 0.3683)
							(mid -0.321484 0.511984)
							(end -0.1778 0.5715)
						)
						(arc
							(start 0.1778 0.5715)
							(mid 0.321484 0.511984)
							(end 0.381 0.3683)
						)
						(arc
							(start 0.381 -0.3683)
							(mid 0.321484 -0.511984)
							(end 0.1778 -0.5715)
						)
					)
					(width 0)
					(fill yes)
				)
			)
		)
		(pad "S" smd custom
			(at -0.98425 0.9525 270)
			(size 0.1905 0.1905)
			(layers "B.Cu" "B.Mask" "B.Paste")
			(net "GND")
			(options
				(clearance outline)
				(anchor circle)
			)
			(primitives
				(gr_poly
					(pts
						(arc
							(start -0.1778 -0.5715)
							(mid -0.321484 -0.511984)
							(end -0.381 -0.3683)
						)
						(arc
							(start -0.381 0.3683)
							(mid -0.321484 0.511984)
							(end -0.1778 0.5715)
						)
						(arc
							(start 0.1778 0.5715)
							(mid 0.321484 0.511984)
							(end 0.381 0.3683)
						)
						(arc
							(start 0.381 -0.3683)
							(mid 0.321484 -0.511984)
							(end 0.1778 -0.5715)
						)
					)
					(width 0)
					(fill yes)
				)
			)
		)
	)
	(footprint ""
		(layer "B.Cu")
		(at 104.267 -44.2214 180)
		(property "Reference" "C77"
			(at 0 0 0)
			(layer "B.SilkS")
			(hide yes)
			(effects
				(font
					(size 1.27 1.27)
				)
				(justify mirror)
			)
		)
		(property "Value" "SCD01U16V1KX-GP"
			(at 2.8321 -1.7399 180)
			(unlocked yes)
			(layer "B.Fab")
			(hide yes)
			(effects
				(font
					(size 1.016 1.016)
					(thickness 0.1524)
				)
				(justify mirror)
			)
		)
		(property "Device Type" "C0201H13"
			(at 2.8321 -3.2639 180)
			(unlocked yes)
			(layer "B.Fab")
			(hide yes)
			(effects
				(font
					(size 1.016 1.016)
					(thickness 0.1524)
				)
				(justify mirror)
			)
		)
		(duplicate_pad_numbers_are_jumpers no)
		(fp_rect
			(start 0.2794 0.6477)
			(end -0.2794 -0.6477)
			(stroke
				(width 0)
				(type default)
			)
			(fill no)
			(layer "B.CrtYd")
		)
		(fp_rect
			(start 0.2794 0.6477)
			(end -0.2794 -0.6477)
			(stroke
				(width 0)
				(type default)
			)
			(fill no)
			(layer "B.Fab")
		)
		(pad "1" smd custom
			(at 0 -0.2794)
			(size 0.0762 0.0762)
			(layers "B.Cu" "B.Mask" "B.Paste")
			(net "PHY_DPB_TO_SCC_21_DN")
			(options
				(clearance outline)
				(anchor circle)
			)
			(primitives
				(gr_poly
					(pts
						(arc
							(start 0.1524 0.127)
							(mid 0.137521 0.162921)
							(end 0.1016 0.1778)
						)
						(arc
							(start -0.1016 0.1778)
							(mid -0.137521 0.162921)
							(end -0.1524 0.127)
						)
						(arc
							(start -0.1524 -0.127)
							(mid -0.137521 -0.162921)
							(end -0.1016 -0.1778)
						)
						(arc
							(start 0.1016 -0.1778)
							(mid 0.137521 -0.162921)
							(end 0.1524 -0.127)
						)
					)
					(width 0)
					(fill yes)
				)
			)
		)
		(pad "2" smd custom
			(at 0 0.2794)
			(size 0.0762 0.0762)
			(layers "B.Cu" "B.Mask" "B.Paste")
			(net "PHY_DPB_TO_SCC_C_21_DN")
			(options
				(clearance outline)
				(anchor circle)
			)
			(primitives
				(gr_poly
					(pts
						(arc
							(start 0.1524 0.127)
							(mid 0.137521 0.162921)
							(end 0.1016 0.1778)
						)
						(arc
							(start -0.1016 0.1778)
							(mid -0.137521 0.162921)
							(end -0.1524 0.127)
						)
						(arc
							(start -0.1524 -0.127)
							(mid -0.137521 -0.162921)
							(end -0.1016 -0.1778)
						)
						(arc
							(start 0.1016 -0.1778)
							(mid 0.137521 -0.162921)
							(end 0.1524 -0.127)
						)
					)
					(width 0)
					(fill yes)
				)
			)
		)
	)
	(footprint ""
		(layer "B.Cu")
		(at 99.695 -44.2214 180)
		(property "Reference" "C84"
			(at 0 0 0)
			(layer "B.SilkS")
			(hide yes)
			(effects
				(font
					(size 1.27 1.27)
				)
				(justify mirror)
			)
		)
		(property "Value" "SCD01U16V1KX-GP"
			(at 2.8321 -1.7399 180)
			(unlocked yes)
			(layer "B.Fab")
			(hide yes)
			(effects
				(font
					(size 1.016 1.016)
					(thickness 0.1524)
				)
				(justify mirror)
			)
		)
		(property "Device Type" "C0201H13"
			(at 2.8321 -3.2639 180)
			(unlocked yes)
			(layer "B.Fab")
			(hide yes)
			(effects
				(font
					(size 1.016 1.016)
					(thickness 0.1524)
				)
				(justify mirror)
			)
		)
		(duplicate_pad_numbers_are_jumpers no)
		(fp_rect
			(start 0.2794 0.6477)
			(end -0.2794 -0.6477)
			(stroke
				(width 0)
				(type default)
			)
			(fill no)
			(layer "B.CrtYd")
		)
		(fp_rect
			(start 0.2794 0.6477)
			(end -0.2794 -0.6477)
			(stroke
				(width 0)
				(type default)
			)
			(fill no)
			(layer "B.Fab")
		)
		(pad "1" smd custom
			(at 0 -0.2794)
			(size 0.0762 0.0762)
			(layers "B.Cu" "B.Mask" "B.Paste")
			(net "PHY_DPB_TO_SCC_18_DN")
			(options
				(clearance outline)
				(anchor circle)
			)
			(primitives
				(gr_poly
					(pts
						(arc
							(start 0.1524 0.127)
							(mid 0.137521 0.162921)
							(end 0.1016 0.1778)
						)
						(arc
							(start -0.1016 0.1778)
							(mid -0.137521 0.162921)
							(end -0.1524 0.127)
						)
						(arc
							(start -0.1524 -0.127)
							(mid -0.137521 -0.162921)
							(end -0.1016 -0.1778)
						)
						(arc
							(start 0.1016 -0.1778)
							(mid 0.137521 -0.162921)
							(end 0.1524 -0.127)
						)
					)
					(width 0)
					(fill yes)
				)
			)
		)
		(pad "2" smd custom
			(at 0 0.2794)
			(size 0.0762 0.0762)
			(layers "B.Cu" "B.Mask" "B.Paste")
			(net "PHY_DPB_TO_SCC_C_18_DN")
			(options
				(clearance outline)
				(anchor circle)
			)
			(primitives
				(gr_poly
					(pts
						(arc
							(start 0.1524 0.127)
							(mid 0.137521 0.162921)
							(end 0.1016 0.1778)
						)
						(arc
							(start -0.1016 0.1778)
							(mid -0.137521 0.162921)
							(end -0.1524 0.127)
						)
						(arc
							(start -0.1524 -0.127)
							(mid -0.137521 -0.162921)
							(end -0.1016 -0.1778)
						)
						(arc
							(start 0.1016 -0.1778)
							(mid 0.137521 -0.162921)
							(end 0.1524 -0.127)
						)
					)
					(width 0)
					(fill yes)
				)
			)
		)
	)
	(footprint ""
		(layer "B.Cu")
		(at 187.87872 -110.14456 180)
		(property "Reference" "D2"
			(at 0 0 0)
			(layer "B.SilkS")
			(hide yes)
			(effects
				(font
					(size 1.27 1.27)
				)
				(justify mirror)
			)
		)
		(property "Value" "RB551V30-GP"
			(at 0 -6.7818 180)
			(unlocked yes)
			(layer "B.Fab")
			(hide yes)
			(effects
				(font
					(size 1.016 1.016)
					(thickness 0.1524)
				)
				(justify mirror)
			)
		)
		(property "Device Type" "SOD323AKH38"
			(at 0 -8.6868 180)
			(unlocked yes)
			(layer "B.Fab")
			(hide yes)
			(effects
				(font
					(size 1.016 1.016)
					(thickness 0.1524)
				)
				(justify mirror)
			)
		)
		(duplicate_pad_numbers_are_jumpers no)
		(fp_line
			(start 0.889 2.159)
			(end 0.889 -1.9304)
			(stroke
				(width 0.1524)
				(type default)
			)
			(layer "B.SilkS")
		)
		(fp_line
			(start 0.889 -1.9304)
			(end -0.889 -1.9304)
			(stroke
				(width 0.1524)
				(type default)
			)
			(layer "B.SilkS")
		)
		(fp_line
			(start -0.762 2.0574)
			(end 0.762 2.0574)
			(stroke
				(width 0.508)
				(type default)
			)
			(layer "B.SilkS")
		)
		(fp_line
			(start -0.889 2.159)
			(end 0.889 2.159)
			(stroke
				(width 0.1524)
				(type default)
			)
			(layer "B.SilkS")
		)
		(fp_line
			(start -0.889 -1.9304)
			(end -0.889 2.159)
			(stroke
				(width 0.1524)
				(type default)
			)
			(layer "B.SilkS")
		)
		(fp_rect
			(start 1.016 2.3114)
			(end -1.016 -2.0066)
			(stroke
				(width 0)
				(type default)
			)
			(fill no)
			(layer "B.CrtYd")
		)
		(fp_poly
			(pts
				(xy 1.016 -2.0066) (xy -1.016 -2.0066) (xy -1.016 2.3114) (xy 1.016 2.3114)
			)
			(stroke
				(width 0)
				(type default)
			)
			(fill no)
			(layer "B.Fab")
		)
		(pad "A" smd rect
			(at 0 -1.143)
			(size 0.5588 1.016)
			(layers "B.Cu" "B.Mask" "B.Paste")
			(net "P1V8_C_S")
		)
		(pad "K" smd rect
			(at 0 1.143)
			(size 0.5588 1.016)
			(layers "B.Cu" "B.Mask" "B.Paste")
			(net "P0V9_PG")
		)
	)
	(footprint ""
		(layer "B.Cu")
		(at 80.463644 -98.613468)
		(property "Reference" "R149"
			(at 0 0 0)
			(layer "B.SilkS")
			(hide yes)
			(effects
				(font
					(size 1.27 1.27)
				)
				(justify mirror)
			)
		)
		(property "Value" "10KR2F-2-GP"
			(at -0.064008 -3.993896 0)
			(unlocked yes)
			(layer "B.Fab")
			(hide yes)
			(effects
				(font
					(size 1.016 1.016)
					(thickness 0.1524)
				)
				(justify mirror)
			)
		)
		(property "Device Type" "R402H16"
			(at -0.064008 -5.517896 0)
			(unlocked yes)
			(layer "B.Fab")
			(hide yes)
			(effects
				(font
					(size 1.016 1.016)
					(thickness 0.1524)
				)
				(justify mirror)
			)
		)
		(duplicate_pad_numbers_are_jumpers no)
		(fp_line
			(start -0.508 -0.9398)
			(end 0.508 -0.9398)
			(stroke
				(width 0.1524)
				(type default)
			)
			(layer "B.SilkS")
		)
		(fp_line
			(start 0.508 -0.9398)
			(end 0.508 0.9398)
			(stroke
				(width 0.1524)
				(type default)
			)
			(layer "B.SilkS")
		)
		(fp_rect
			(start 0.508 0.9398)
			(end -0.508 -0.9398)
			(stroke
				(width 0)
				(type default)
			)
			(fill no)
			(layer "B.CrtYd")
		)
		(fp_rect
			(start 0.508 0.9398)
			(end -0.508 -0.9398)
			(stroke
				(width 0)
				(type default)
			)
			(fill no)
			(layer "B.Fab")
		)
		(pad "1" smd custom
			(at 0 -0.4445 180)
			(size 0.1397 0.1397)
			(layers "B.Cu" "B.Mask" "B.Paste")
			(net "P1V8_E")
			(options
				(clearance outline)
				(anchor circle)
			)
			(primitives
				(gr_poly
					(pts
						(arc
							(start -0.1778 0.2794)
							(mid -0.249642 0.249642)
							(end -0.2794 0.1778)
						)
						(arc
							(start -0.2794 -0.1778)
							(mid -0.249642 -0.249642)
							(end -0.1778 -0.2794)
						)
						(arc
							(start 0.1778 -0.2794)
							(mid 0.249642 -0.249642)
							(end 0.2794 -0.1778)
						)
						(arc
							(start 0.2794 0.1778)
							(mid 0.249642 0.249642)
							(end 0.1778 0.2794)
						)
					)
					(width 0)
					(fill yes)
				)
			)
		)
		(pad "2" smd custom
			(at 0 0.4445 180)
			(size 0.1397 0.1397)
			(layers "B.Cu" "B.Mask" "B.Paste")
			(net "EXP_WP_N")
			(options
				(clearance outline)
				(anchor circle)
			)
			(primitives
				(gr_poly
					(pts
						(arc
							(start -0.1778 0.2794)
							(mid -0.249642 0.249642)
							(end -0.2794 0.1778)
						)
						(arc
							(start -0.2794 -0.1778)
							(mid -0.249642 -0.249642)
							(end -0.1778 -0.2794)
						)
						(arc
							(start 0.1778 -0.2794)
							(mid 0.249642 -0.249642)
							(end 0.2794 -0.1778)
						)
						(arc
							(start 0.2794 0.1778)
							(mid 0.249642 0.249642)
							(end 0.1778 0.2794)
						)
					)
					(width 0)
					(fill yes)
				)
			)
		)
	)
	(footprint ""
		(layer "B.Cu")
		(at 122.4788 -60.4774 -90)
		(property "Reference" "C590"
			(at 0 0 90)
			(layer "B.SilkS")
			(hide yes)
			(effects
				(font
					(size 1.27 1.27)
				)
				(justify mirror)
			)
		)
		(property "Value" "SCD1U6D3V1KX-GP"
			(at 2.8321 -1.7399 270)
			(unlocked yes)
			(layer "B.Fab")
			(hide yes)
			(effects
				(font
					(size 1.016 1.016)
					(thickness 0.1524)
				)
				(justify mirror)
			)
		)
		(property "Device Type" "C0201H13"
			(at 2.8321 -3.2639 270)
			(unlocked yes)
			(layer "B.Fab")
			(hide yes)
			(effects
				(font
					(size 1.016 1.016)
					(thickness 0.1524)
				)
				(justify mirror)
			)
		)
		(duplicate_pad_numbers_are_jumpers no)
		(fp_rect
			(start 0.2794 0.6477)
			(end -0.2794 -0.6477)
			(stroke
				(width 0)
				(type default)
			)
			(fill no)
			(layer "B.CrtYd")
		)
		(fp_rect
			(start 0.2794 0.6477)
			(end -0.2794 -0.6477)
			(stroke
				(width 0)
				(type default)
			)
			(fill no)
			(layer "B.Fab")
		)
		(pad "1" smd custom
			(at 0 -0.2794 90)
			(size 0.0762 0.0762)
			(layers "B.Cu" "B.Mask" "B.Paste")
			(net "GB_VDDA")
			(options
				(clearance outline)
				(anchor circle)
			)
			(primitives
				(gr_poly
					(pts
						(arc
							(start 0.1524 0.127)
							(mid 0.137521 0.162921)
							(end 0.1016 0.1778)
						)
						(arc
							(start -0.1016 0.1778)
							(mid -0.137521 0.162921)
							(end -0.1524 0.127)
						)
						(arc
							(start -0.1524 -0.127)
							(mid -0.137521 -0.162921)
							(end -0.1016 -0.1778)
						)
						(arc
							(start 0.1016 -0.1778)
							(mid 0.137521 -0.162921)
							(end 0.1524 -0.127)
						)
					)
					(width 0)
					(fill yes)
				)
			)
		)
		(pad "2" smd custom
			(at 0 0.2794 90)
			(size 0.0762 0.0762)
			(layers "B.Cu" "B.Mask" "B.Paste")
			(net "GND")
			(options
				(clearance outline)
				(anchor circle)
			)
			(primitives
				(gr_poly
					(pts
						(arc
							(start 0.1524 0.127)
							(mid 0.137521 0.162921)
							(end 0.1016 0.1778)
						)
						(arc
							(start -0.1016 0.1778)
							(mid -0.137521 0.162921)
							(end -0.1524 0.127)
						)
						(arc
							(start -0.1524 -0.127)
							(mid -0.137521 -0.162921)
							(end -0.1016 -0.1778)
						)
						(arc
							(start 0.1016 -0.1778)
							(mid 0.137521 -0.162921)
							(end 0.1524 -0.127)
						)
					)
					(width 0)
					(fill yes)
				)
			)
		)
	)
)
